(kicad_pcb
	(version 20260206)
	(generator "pcbnew")
	(generator_version "10.0")
	(general
		(thickness 1.6)
		(legacy_teardrops no)
	)
	(paper "A4")
	(title_block
		(title "Bryce Canyon_F.DPB_16315-1-OCP.brd")
		(comment 1 "Bryce Canyon / footprints 802-808 of 2223")
	)
	(layers
		(0 "F.Cu" signal "TOP")
		(4 "In1.Cu" signal "L2GND")
		(6 "In2.Cu" signal "L3")
		(8 "In3.Cu" signal "L4GND")
		(10 "In4.Cu" signal "L5")
		(12 "In5.Cu" signal "L6VCC")
		(14 "In6.Cu" signal "L7VCC")
		(16 "In7.Cu" signal "L8")
		(18 "In8.Cu" signal "L9GND")
		(20 "In9.Cu" signal "L10")
		(22 "In10.Cu" signal "L11GND")
		(2 "B.Cu" signal "BOTTOM")
		(9 "F.Adhes" user "F.Adhesive")
		(11 "B.Adhes" user "B.Adhesive")
		(13 "F.Paste" user "Package Geometry/Pastemask Top")
		(15 "B.Paste" user "Package Geometry/Pastemask Bottom")
		(5 "F.SilkS" user "Ref Des/Silkscreen Top")
		(7 "B.SilkS" user "Ref Des/Silkscreen Bottom")
		(1 "F.Mask" user "Board Geometry/Soldermask Top")
		(3 "B.Mask" user "Board Geometry/Soldermask Bottom")
		(17 "Dwgs.User" user "User.Drawings")
		(19 "Cmts.User" user "User.Comments")
		(21 "Eco1.User" user "User.Eco1")
		(23 "Eco2.User" user "User.Eco2")
		(25 "Edge.Cuts" user "Board Geometry/Outline")
		(27 "Margin" user)
		(31 "F.CrtYd" user "Package Geometry/Place Bound Top")
		(29 "B.CrtYd" user "Package Geometry/Place Bound Bottom")
		(35 "F.Fab" user "Ref Des/Assembly Top")
		(33 "B.Fab" user "Ref Des/Assembly Bottom")
	)
	(footprint ""
		(layer "F.Cu")
		(at 180.7464 -274.821142 -90)
		(property "Reference" "R256"
			(at 0 0 270)
			(layer "F.SilkS")
			(hide yes)
			(effects
				(font
					(size 1.27 1.27)
				)
			)
		)
		(property "Value" "0R2J-2-GP"
			(at 0.064008 -3.993896 270)
			(unlocked yes)
			(layer "F.Fab")
			(hide yes)
			(effects
				(font
					(size 1.016 1.016)
					(thickness 0.1524)
				)
			)
		)
		(property "Device Type" "R402H16"
			(at 0.064008 -5.517896 270)
			(unlocked yes)
			(layer "F.Fab")
			(hide yes)
			(effects
				(font
					(size 1.016 1.016)
					(thickness 0.1524)
				)
			)
		)
		(duplicate_pad_numbers_are_jumpers no)
		(fp_line
			(start -0.508 -0.9398)
			(end -0.508 0.9398)
			(stroke
				(width 0.1524)
				(type default)
			)
			(layer "F.SilkS")
		)
		(fp_line
			(start 0.508 -0.9398)
			(end -0.508 -0.9398)
			(stroke
				(width 0.1524)
				(type default)
			)
			(layer "F.SilkS")
		)
		(fp_rect
			(start -0.508 0.9398)
			(end 0.508 -0.9398)
			(stroke
				(width 0)
				(type default)
			)
			(fill no)
			(layer "F.CrtYd")
		)
		(fp_rect
			(start -0.508 0.9398)
			(end 0.508 -0.9398)
			(stroke
				(width 0)
				(type default)
			)
			(fill no)
			(layer "F.Fab")
		)
		(pad "1" smd custom
			(at 0 -0.4445 270)
			(size 0.1397 0.1397)
			(layers "F.Cu" "F.Mask" "F.Paste")
			(net "DRIVE_A_5_PWR")
			(options
				(clearance outline)
				(anchor circle)
			)
			(primitives
				(gr_poly
					(pts
						(arc
							(start -0.1778 -0.2794)
							(mid -0.249642 -0.249642)
							(end -0.2794 -0.1778)
						)
						(arc
							(start -0.2794 0.1778)
							(mid -0.249642 0.249642)
							(end -0.1778 0.2794)
						)
						(arc
							(start 0.1778 0.2794)
							(mid 0.249642 0.249642)
							(end 0.2794 0.1778)
						)
						(arc
							(start 0.2794 -0.1778)
							(mid 0.249642 -0.249642)
							(end 0.1778 -0.2794)
						)
					)
					(width 0)
					(fill yes)
				)
			)
		)
		(pad "2" smd custom
			(at 0 0.4445 270)
			(size 0.1397 0.1397)
			(layers "F.Cu" "F.Mask" "F.Paste")
			(net "SW_PWR_R_HDD5")
			(options
				(clearance outline)
				(anchor circle)
			)
			(primitives
				(gr_poly
					(pts
						(arc
							(start -0.1778 -0.2794)
							(mid -0.249642 -0.249642)
							(end -0.2794 -0.1778)
						)
						(arc
							(start -0.2794 0.1778)
							(mid -0.249642 0.249642)
							(end -0.1778 0.2794)
						)
						(arc
							(start 0.1778 0.2794)
							(mid 0.249642 0.249642)
							(end 0.2794 0.1778)
						)
						(arc
							(start 0.2794 -0.1778)
							(mid 0.249642 -0.249642)
							(end 0.1778 -0.2794)
						)
					)
					(width 0)
					(fill yes)
				)
			)
		)
	)
	(footprint ""
		(layer "F.Cu")
		(at 230.321104 -346.908882 -90)
		(property "Reference" "U3"
			(at 0 0 270)
			(layer "F.SilkS")
			(hide yes)
			(effects
				(font
					(size 1.27 1.27)
				)
			)
		)
		(property "Value" "ADC128D818CIMTX-NOPB-1-GP"
			(at 0.127 -12.573 270)
			(unlocked yes)
			(layer "F.Fab")
			(hide yes)
			(effects
				(font
					(size 1.016 1.016)
					(thickness 0.1524)
				)
			)
		)
		(property "Device Type" "TSOIC16H48"
			(at 0.1016 -14.5796 270)
			(unlocked yes)
			(layer "F.Fab")
			(hide yes)
			(effects
				(font
					(size 1.016 1.016)
					(thickness 0.1524)
				)
			)
		)
		(duplicate_pad_numbers_are_jumpers no)
		(fp_line
			(start -2.921 3.81)
			(end -2.921 1.778)
			(stroke
				(width 0.508)
				(type default)
			)
			(layer "F.SilkS")
		)
		(fp_line
			(start 2.3622 1.778)
			(end -2.921 1.778)
			(stroke
				(width 0.1524)
				(type default)
			)
			(layer "F.SilkS")
		)
		(fp_line
			(start -2.54 0)
			(end -3.0988 0.5588)
			(stroke
				(width 0.1524)
				(type default)
			)
			(layer "F.SilkS")
		)
		(fp_line
			(start -2.54 0)
			(end -3.0988 -0.5588)
			(stroke
				(width 0.1524)
				(type default)
			)
			(layer "F.SilkS")
		)
		(fp_line
			(start -3.0988 -1.778)
			(end -3.0988 1.778)
			(stroke
				(width 0.1524)
				(type default)
			)
			(layer "F.SilkS")
		)
		(fp_line
			(start -3.0988 -1.778)
			(end 2.3622 -1.778)
			(stroke
				(width 0.1524)
				(type default)
			)
			(layer "F.SilkS")
		)
		(fp_line
			(start 2.3622 -1.778)
			(end 2.3622 1.778)
			(stroke
				(width 0.1524)
				(type default)
			)
			(layer "F.SilkS")
		)
		(fp_poly
			(pts
				(xy -2.4638 -1.778) (xy -2.4638 1.778) (xy 2.3622 1.778) (xy 2.3622 -1.778)
			)
			(stroke
				(width 0)
				(type default)
			)
			(fill yes)
			(layer "F.SilkS")
		)
		(fp_rect
			(start -3.175 4.064)
			(end 3.175 -4.064)
			(stroke
				(width 0)
				(type default)
			)
			(fill no)
			(layer "F.CrtYd")
		)
		(fp_poly
			(pts
				(xy -3.175 -4.064) (xy 3.175 -4.064) (xy 3.175 4.064) (xy -3.175 4.064)
			)
			(stroke
				(width 0)
				(type default)
			)
			(fill no)
			(layer "F.Fab")
		)
		(pad "1" smd rect
			(at -2.27584 2.8194 270)
			(size 0.3556 1.524)
			(layers "F.Cu" "F.Mask" "F.Paste")
			(net "Net_333")
		)
		(pad "2" smd rect
			(at -1.6256 2.8194 270)
			(size 0.3556 1.524)
			(layers "F.Cu" "F.Mask" "F.Paste")
			(net "VOL_SEN_SDA")
		)
		(pad "3" smd rect
			(at -0.97536 2.8194 270)
			(size 0.3556 1.524)
			(layers "F.Cu" "F.Mask" "F.Paste")
			(net "VOL_SEN_SCL")
		)
		(pad "4" smd rect
			(at -0.32512 2.8194 270)
			(size 0.3556 1.524)
			(layers "F.Cu" "F.Mask" "F.Paste")
			(net "GND")
		)
		(pad "5" smd rect
			(at 0.32512 2.8194 270)
			(size 0.3556 1.524)
			(layers "F.Cu" "F.Mask" "F.Paste")
			(net "P3V3_STBY_A")
		)
		(pad "6" smd rect
			(at 0.97536 2.8194 270)
			(size 0.3556 1.524)
			(layers "F.Cu" "F.Mask" "F.Paste")
			(net "VOL_SEN_INT_N")
		)
		(pad "7" smd rect
			(at 1.6256 2.8194 270)
			(size 0.3556 1.524)
			(layers "F.Cu" "F.Mask" "F.Paste")
			(net "VOL_SEN_ADDR0")
		)
		(pad "8" smd rect
			(at 2.27584 2.8194 270)
			(size 0.3556 1.524)
			(layers "F.Cu" "F.Mask" "F.Paste")
			(net "VOL_SEN_ADDR1")
		)
		(pad "9" smd rect
			(at 2.27584 -2.8194 270)
			(size 0.3556 1.524)
			(layers "F.Cu" "F.Mask" "F.Paste")
			(net "Net_334")
		)
		(pad "10" smd rect
			(at 1.6256 -2.8194 270)
			(size 0.3556 1.524)
			(layers "F.Cu" "F.Mask" "F.Paste")
			(net "Net_335")
		)
		(pad "11" smd rect
			(at 0.97536 -2.8194 270)
			(size 0.3556 1.524)
			(layers "F.Cu" "F.Mask" "F.Paste")
			(net "Net_336")
		)
		(pad "12" smd rect
			(at 0.32512 -2.8194 270)
			(size 0.3556 1.524)
			(layers "F.Cu" "F.Mask" "F.Paste")
			(net "P5V_A_4_SENSE")
		)
		(pad "13" smd rect
			(at -0.32512 -2.8194 270)
			(size 0.3556 1.524)
			(layers "F.Cu" "F.Mask" "F.Paste")
			(net "P5V_A_3_SENSE")
		)
		(pad "14" smd rect
			(at -0.97536 -2.8194 270)
			(size 0.3556 1.524)
			(layers "F.Cu" "F.Mask" "F.Paste")
			(net "P5V_A_2_SENSE")
		)
		(pad "15" smd rect
			(at -1.6256 -2.8194 270)
			(size 0.3556 1.524)
			(layers "F.Cu" "F.Mask" "F.Paste")
			(net "P5V_A_1_SENSE")
		)
		(pad "16" smd rect
			(at -2.27584 -2.8194 270)
			(size 0.3556 1.524)
			(layers "F.Cu" "F.Mask" "F.Paste")
			(net "P3V3_SENSE")
		)
	)
	(footprint ""
		(layer "F.Cu")
		(at 336.348578 -33.554162 180)
		(property "Reference" "R1300"
			(at 0 0 180)
			(layer "F.SilkS")
			(hide yes)
			(effects
				(font
					(size 1.27 1.27)
				)
			)
		)
		(property "Value" "2K2R2F-GP"
			(at 0.064008 -3.993896 180)
			(unlocked yes)
			(layer "F.Fab")
			(hide yes)
			(effects
				(font
					(size 1.016 1.016)
					(thickness 0.1524)
				)
			)
		)
		(property "Device Type" "R402H16"
			(at 0.064008 -5.517896 180)
			(unlocked yes)
			(layer "F.Fab")
			(hide yes)
			(effects
				(font
					(size 1.016 1.016)
					(thickness 0.1524)
				)
			)
		)
		(duplicate_pad_numbers_are_jumpers no)
		(fp_line
			(start 0.508 -0.9398)
			(end -0.508 -0.9398)
			(stroke
				(width 0.1524)
				(type default)
			)
			(layer "F.SilkS")
		)
		(fp_line
			(start -0.508 -0.9398)
			(end -0.508 0.9398)
			(stroke
				(width 0.1524)
				(type default)
			)
			(layer "F.SilkS")
		)
		(fp_rect
			(start -0.508 0.9398)
			(end 0.508 -0.9398)
			(stroke
				(width 0)
				(type default)
			)
			(fill no)
			(layer "F.CrtYd")
		)
		(fp_rect
			(start -0.508 0.9398)
			(end 0.508 -0.9398)
			(stroke
				(width 0)
				(type default)
			)
			(fill no)
			(layer "F.Fab")
		)
		(pad "1" smd custom
			(at 0 -0.4445 180)
			(size 0.1397 0.1397)
			(layers "F.Cu" "F.Mask" "F.Paste")
			(net "P3V3_STBY_B")
			(options
				(clearance outline)
				(anchor circle)
			)
			(primitives
				(gr_poly
					(pts
						(arc
							(start -0.1778 -0.2794)
							(mid -0.249642 -0.249642)
							(end -0.2794 -0.1778)
						)
						(arc
							(start -0.2794 0.1778)
							(mid -0.249642 0.249642)
							(end -0.1778 0.2794)
						)
						(arc
							(start 0.1778 0.2794)
							(mid 0.249642 0.249642)
							(end 0.2794 0.1778)
						)
						(arc
							(start 0.2794 -0.1778)
							(mid 0.249642 -0.249642)
							(end 0.1778 -0.2794)
						)
					)
					(width 0)
					(fill yes)
				)
			)
		)
		(pad "2" smd custom
			(at 0 0.4445 180)
			(size 0.1397 0.1397)
			(layers "F.Cu" "F.Mask" "F.Paste")
			(net "I2C_BMC_B_MISC_SCL")
			(options
				(clearance outline)
				(anchor circle)
			)
			(primitives
				(gr_poly
					(pts
						(arc
							(start -0.1778 -0.2794)
							(mid -0.249642 -0.249642)
							(end -0.2794 -0.1778)
						)
						(arc
							(start -0.2794 0.1778)
							(mid -0.249642 0.249642)
							(end -0.1778 0.2794)
						)
						(arc
							(start 0.1778 0.2794)
							(mid 0.249642 0.249642)
							(end 0.2794 0.1778)
						)
						(arc
							(start 0.2794 -0.1778)
							(mid 0.249642 -0.249642)
							(end 0.1778 -0.2794)
						)
					)
					(width 0)
					(fill yes)
				)
			)
		)
	)
	(footprint ""
		(layer "F.Cu")
		(at 223.5708 -177.038)
		(property "Reference" "C133"
			(at 0 0 0)
			(layer "F.SilkS")
			(hide yes)
			(effects
				(font
					(size 1.27 1.27)
				)
			)
		)
		(property "Value" "SC2D2U25V5KX-2-GP"
			(at -0.0762 -6.1214 0)
			(unlocked yes)
			(layer "F.Fab")
			(hide yes)
			(effects
				(font
					(size 1.016 1.016)
					(thickness 0.1524)
				)
			)
		)
		(property "Device Type" "C805H54"
			(at -0.0762 -8.1534 0)
			(unlocked yes)
			(layer "F.Fab")
			(hide yes)
			(effects
				(font
					(size 1.016 1.016)
					(thickness 0.1524)
				)
			)
		)
		(duplicate_pad_numbers_are_jumpers no)
		(fp_line
			(start 0.635 0)
			(end -0.635 0)
			(stroke
				(width 0.508)
				(type default)
			)
			(layer "F.SilkS")
		)
		(fp_rect
			(start -0.9652 1.778)
			(end 0.9652 -1.778)
			(stroke
				(width 0)
				(type default)
			)
			(fill no)
			(layer "F.CrtYd")
		)
		(fp_poly
			(pts
				(xy -0.9652 -1.778) (xy 0.9652 -1.778) (xy 0.9652 1.778) (xy -0.9652 1.778)
			)
			(stroke
				(width 0)
				(type default)
			)
			(fill no)
			(layer "F.Fab")
		)
		(pad "1" smd rect
			(at 0 -0.9652)
			(size 1.397 1.143)
			(layers "F.Cu" "F.Mask" "F.Paste")
			(net "P12V_A_COMP")
		)
		(pad "2" smd rect
			(at 0 0.9652)
			(size 1.397 1.143)
			(layers "F.Cu" "F.Mask" "F.Paste")
			(net "GND")
		)
	)
	(footprint ""
		(layer "F.Cu")
		(at 272.669 -272.288)
		(property "Reference" "R111"
			(at 0 0 0)
			(layer "F.SilkS")
			(hide yes)
			(effects
				(font
					(size 1.27 1.27)
				)
			)
		)
		(property "Value" "4K7R2F-GP"
			(at 0.064008 -3.993896 0)
			(unlocked yes)
			(layer "F.Fab")
			(hide yes)
			(effects
				(font
					(size 1.016 1.016)
					(thickness 0.1524)
				)
			)
		)
		(property "Device Type" "R402H16"
			(at 0.064008 -5.517896 0)
			(unlocked yes)
			(layer "F.Fab")
			(hide yes)
			(effects
				(font
					(size 1.016 1.016)
					(thickness 0.1524)
				)
			)
		)
		(duplicate_pad_numbers_are_jumpers no)
		(fp_line
			(start -0.508 -0.9398)
			(end -0.508 0.9398)
			(stroke
				(width 0.1524)
				(type default)
			)
			(layer "F.SilkS")
		)
		(fp_line
			(start 0.508 -0.9398)
			(end -0.508 -0.9398)
			(stroke
				(width 0.1524)
				(type default)
			)
			(layer "F.SilkS")
		)
		(fp_rect
			(start -0.508 0.9398)
			(end 0.508 -0.9398)
			(stroke
				(width 0)
				(type default)
			)
			(fill no)
			(layer "F.CrtYd")
		)
		(fp_rect
			(start -0.508 0.9398)
			(end 0.508 -0.9398)
			(stroke
				(width 0)
				(type default)
			)
			(fill no)
			(layer "F.Fab")
		)
		(pad "1" smd custom
			(at 0 -0.4445)
			(size 0.1397 0.1397)
			(layers "F.Cu" "F.Mask" "F.Paste")
			(net "IO_EXP1_HDD_FAULT_A1")
			(options
				(clearance outline)
				(anchor circle)
			)
			(primitives
				(gr_poly
					(pts
						(arc
							(start -0.1778 -0.2794)
							(mid -0.249642 -0.249642)
							(end -0.2794 -0.1778)
						)
						(arc
							(start -0.2794 0.1778)
							(mid -0.249642 0.249642)
							(end -0.1778 0.2794)
						)
						(arc
							(start 0.1778 0.2794)
							(mid 0.249642 0.249642)
							(end 0.2794 0.1778)
						)
						(arc
							(start 0.2794 -0.1778)
							(mid 0.249642 -0.249642)
							(end 0.1778 -0.2794)
						)
					)
					(width 0)
					(fill yes)
				)
			)
		)
		(pad "2" smd custom
			(at 0 0.4445)
			(size 0.1397 0.1397)
			(layers "F.Cu" "F.Mask" "F.Paste")
			(net "GND")
			(options
				(clearance outline)
				(anchor circle)
			)
			(primitives
				(gr_poly
					(pts
						(arc
							(start -0.1778 -0.2794)
							(mid -0.249642 -0.249642)
							(end -0.2794 -0.1778)
						)
						(arc
							(start -0.2794 0.1778)
							(mid -0.249642 0.249642)
							(end -0.1778 0.2794)
						)
						(arc
							(start 0.1778 0.2794)
							(mid 0.249642 0.249642)
							(end 0.2794 0.1778)
						)
						(arc
							(start 0.2794 -0.1778)
							(mid 0.249642 -0.249642)
							(end 0.1778 -0.2794)
						)
					)
					(width 0)
					(fill yes)
				)
			)
		)
	)
	(footprint ""
		(layer "F.Cu")
		(at 239.973104 -238.252)
		(property "Reference" "C25"
			(at 0 0 0)
			(layer "F.SilkS")
			(hide yes)
			(effects
				(font
					(size 1.27 1.27)
				)
			)
		)
		(property "Value" "SC1U16V3KX-5GP"
			(at 0 -2.8194 0)
			(unlocked yes)
			(layer "F.Fab")
			(hide yes)
			(effects
				(font
					(size 1.016 1.016)
					(thickness 0.1524)
				)
			)
		)
		(property "Device Type" "C603H36"
			(at 0 -4.3434 0)
			(unlocked yes)
			(layer "F.Fab")
			(hide yes)
			(effects
				(font
					(size 1.016 1.016)
					(thickness 0.1524)
				)
			)
		)
		(duplicate_pad_numbers_are_jumpers no)
		(fp_line
			(start 0.508 0)
			(end -0.508 0)
			(stroke
				(width 0.2032)
				(type default)
			)
			(layer "F.SilkS")
		)
		(fp_rect
			(start -0.5842 1.3335)
			(end 0.5842 -1.3335)
			(stroke
				(width 0)
				(type default)
			)
			(fill no)
			(layer "F.CrtYd")
		)
		(fp_rect
			(start -0.5842 1.3335)
			(end 0.5842 -1.3335)
			(stroke
				(width 0)
				(type default)
			)
			(fill no)
			(layer "F.Fab")
		)
		(pad "1" smd custom
			(at 0 -0.762)
			(size 0.2159 0.2159)
			(layers "F.Cu" "F.Mask" "F.Paste")
			(net "GPIO_VCC_U8")
			(options
				(clearance outline)
				(anchor circle)
			)
			(primitives
				(gr_poly
					(pts
						(arc
							(start -0.3302 -0.4318)
							(mid -0.402042 -0.402042)
							(end -0.4318 -0.3302)
						)
						(arc
							(start -0.4318 0.3302)
							(mid -0.402042 0.402042)
							(end -0.3302 0.4318)
						)
						(arc
							(start 0.3302 0.4318)
							(mid 0.402042 0.402042)
							(end 0.4318 0.3302)
						)
						(arc
							(start 0.4318 -0.3302)
							(mid 0.402042 -0.402042)
							(end 0.3302 -0.4318)
						)
					)
					(width 0)
					(fill yes)
				)
			)
		)
		(pad "2" smd custom
			(at 0 0.762)
			(size 0.2159 0.2159)
			(layers "F.Cu" "F.Mask" "F.Paste")
			(net "GND")
			(options
				(clearance outline)
				(anchor circle)
			)
			(primitives
				(gr_poly
					(pts
						(arc
							(start -0.3302 -0.4318)
							(mid -0.402042 -0.402042)
							(end -0.4318 -0.3302)
						)
						(arc
							(start -0.4318 0.3302)
							(mid -0.402042 0.402042)
							(end -0.3302 0.4318)
						)
						(arc
							(start 0.3302 0.4318)
							(mid 0.402042 0.402042)
							(end 0.4318 0.3302)
						)
						(arc
							(start 0.4318 -0.3302)
							(mid 0.402042 -0.402042)
							(end 0.3302 -0.4318)
						)
					)
					(width 0)
					(fill yes)
				)
			)
		)
	)
	(footprint ""
		(layer "F.Cu")
		(at 239.491266 -346.343478 180)
		(property "Reference" "C50"
			(at 0 0 180)
			(layer "F.SilkS")
			(hide yes)
			(effects
				(font
					(size 1.27 1.27)
				)
			)
		)
		(property "Value" "SCD1U16V2KX-3GP"
			(at 1.1811 -2.7051 180)
			(unlocked yes)
			(layer "F.Fab")
			(hide yes)
			(effects
				(font
					(size 1.016 1.016)
					(thickness 0.1524)
				)
			)
		)
		(property "Device Type" "C402H22"
			(at 1.1811 -4.2291 180)
			(unlocked yes)
			(layer "F.Fab")
			(hide yes)
			(effects
				(font
					(size 1.016 1.016)
					(thickness 0.1524)
				)
			)
		)
		(duplicate_pad_numbers_are_jumpers no)
		(fp_rect
			(start -0.4318 0.9525)
			(end 0.4318 -0.9525)
			(stroke
				(width 0)
				(type default)
			)
			(fill no)
			(layer "F.CrtYd")
		)
		(fp_rect
			(start -0.4318 0.9525)
			(end 0.4318 -0.9525)
			(stroke
				(width 0)
				(type default)
			)
			(fill no)
			(layer "F.Fab")
		)
		(pad "1" smd custom
			(at 0 -0.4445 180)
			(size 0.1524 0.1524)
			(layers "F.Cu" "F.Mask" "F.Paste")
			(net "P5V_A_3_SENSE")
			(options
				(clearance outline)
				(anchor circle)
			)
			(primitives
				(gr_poly
					(pts
						(arc
							(start 0.3048 -0.2032)
							(mid 0.275042 -0.275042)
							(end 0.2032 -0.3048)
						)
						(arc
							(start -0.2032 -0.3048)
							(mid -0.275042 -0.275042)
							(end -0.3048 -0.2032)
						)
						(arc
							(start -0.3048 0.2032)
							(mid -0.275042 0.275042)
							(end -0.2032 0.3048)
						)
						(arc
							(start 0.2032 0.3048)
							(mid 0.275042 0.275042)
							(end 0.3048 0.2032)
						)
					)
					(width 0)
					(fill yes)
				)
			)
		)
		(pad "2" smd custom
			(at 0 0.4445 180)
			(size 0.1524 0.1524)
			(layers "F.Cu" "F.Mask" "F.Paste")
			(net "GND")
			(options
				(clearance outline)
				(anchor circle)
			)
			(primitives
				(gr_poly
					(pts
						(arc
							(start 0.3048 -0.2032)
							(mid 0.275042 -0.275042)
							(end 0.2032 -0.3048)
						)
						(arc
							(start -0.2032 -0.3048)
							(mid -0.275042 -0.275042)
							(end -0.3048 -0.2032)
						)
						(arc
							(start -0.3048 0.2032)
							(mid -0.275042 0.275042)
							(end -0.2032 0.3048)
						)
						(arc
							(start 0.2032 0.3048)
							(mid 0.275042 0.275042)
							(end 0.3048 0.2032)
						)
					)
					(width 0)
					(fill yes)
				)
			)
		)
	)
)
